# T6G (Grand Teton) — schematic netlist excerpt (pin names and nets, part order shuffled) for the footprints in the layout excerpt that follows; sources: Cadence DE-HDL packaged netlist, KiCad conversion of 04192023_DAF0TMB3IC0_F0TG_MB_C_brd_V02_OCP.brd

PC6807  Q_CAP  100NF 50V 10% X7R  pkg C0402  page 365 : A = P0V9_CPU1_RT_2D ; B = GND
C2611  Q_CAP  22UF 4V 20% X6S  pkg C0402  page 70 : A = PVDDIO_P0 ; B = GND
C379  Q_CAP  0.1UF 10V 10% X7S  pkg C0201  page 345 : A = P1V8_CPU1_RT2_1A ; B = GND

(kicad_pcb
	(version 20260206)
	(generator "pcbnew")
	(generator_version "10.0")
	(general
		(thickness 1.6)
		(legacy_teardrops no)
	)
	(paper "A4")
	(title_block
		(title "04192023_DAF0TMB3IC0_F0TG_MB_C_brd_V02_OCP.brd")
		(comment 1 "Grand Teton / footprints 6415-6417 of 8354")
	)
	(layers
		(0 "F.Cu" signal "TOP")
		(4 "In1.Cu" signal "GND")
		(6 "In2.Cu" signal "IN1")
		(8 "In3.Cu" signal "GND1")
		(10 "In4.Cu" signal "IN2")
		(12 "In5.Cu" signal "GND2")
		(14 "In6.Cu" signal "IN3")
		(16 "In7.Cu" signal "GND3")
		(18 "In8.Cu" signal "VCC")
		(20 "In9.Cu" signal "VCC1")
		(22 "In10.Cu" signal "GND4")
		(24 "In11.Cu" signal "IN4")
		(26 "In12.Cu" signal "GND5")
		(28 "In13.Cu" signal "IN5")
		(30 "In14.Cu" signal "GND6")
		(32 "In15.Cu" signal "IN6")
		(34 "In16.Cu" signal "GND7")
		(2 "B.Cu" signal "BOTTOM")
		(9 "F.Adhes" user "F.Adhesive")
		(11 "B.Adhes" user "B.Adhesive")
		(13 "F.Paste" user "Package Geometry/Pastemask Top")
		(15 "B.Paste" user "Package Geometry/Pastemask Bottom")
		(5 "F.SilkS" user "Ref Des/Silkscreen Top")
		(7 "B.SilkS" user "Ref Des/Silkscreen Bottom")
		(1 "F.Mask" user "Board Geometry/Soldermask Top")
		(3 "B.Mask" user "Board Geometry/Soldermask Bottom")
		(17 "Dwgs.User" user "User.Drawings")
		(19 "Cmts.User" user "User.Comments")
		(21 "Eco1.User" user "User.Eco1")
		(23 "Eco2.User" user "User.Eco2")
		(25 "Edge.Cuts" user "Board Geometry/Outline")
		(27 "Margin" user)
		(31 "F.CrtYd" user "Package Geometry/Place Bound Top")
		(29 "B.CrtYd" user "Package Geometry/Place Bound Bottom")
		(35 "F.Fab" user "Ref Des/Assembly Top")
		(33 "B.Fab" user "Ref Des/Assembly Bottom")
	)
	(footprint ""
		(layer "B.Cu")
		(at 26.206958 -382.874012 -90)
		(property "Reference" "PC6807"
			(at 0 0 90)
			(layer "B.SilkS")
			(hide yes)
			(effects
				(font
					(size 1.27 1.27)
				)
				(justify mirror)
			)
		)
		(property "Value" ""
			(at 0 0 90)
			(layer "B.Fab")
			(effects
				(font
					(size 1.27 1.27)
				)
				(justify mirror)
			)
		)
		(duplicate_pad_numbers_are_jumpers no)
		(fp_line
			(start -0.7874 0.4064)
			(end 0.7874 0.4064)
			(stroke
				(width 0.1524)
				(type default)
			)
			(layer "B.SilkS")
		)
		(fp_line
			(start 0.7874 0.4064)
			(end 0.7874 -0.4064)
			(stroke
				(width 0.1524)
				(type default)
			)
			(layer "B.SilkS")
		)
		(fp_line
			(start -0.7874 -0.4064)
			(end -0.7874 0.4064)
			(stroke
				(width 0.1524)
				(type default)
			)
			(layer "B.SilkS")
		)
		(fp_line
			(start 0.7874 -0.4064)
			(end -0.7874 -0.4064)
			(stroke
				(width 0.1524)
				(type default)
			)
			(layer "B.SilkS")
		)
		(fp_line
			(start -0.67945 0.3048)
			(end -0.120396 0.3048)
			(stroke
				(width 0.1)
				(type default)
			)
			(layer "B.Fab")
		)
		(fp_line
			(start -0.120396 0.3048)
			(end -0.120396 0.2794)
			(stroke
				(width 0.1)
				(type default)
			)
			(layer "B.Fab")
		)
		(fp_line
			(start 0.12065 0.3048)
			(end 0.67945 0.3048)
			(stroke
				(width 0.1)
				(type default)
			)
			(layer "B.Fab")
		)
		(fp_line
			(start 0.67945 0.3048)
			(end 0.67945 -0.305054)
			(stroke
				(width 0.1)
				(type default)
			)
			(layer "B.Fab")
		)
		(fp_line
			(start -0.120396 0.2794)
			(end 0.12065 0.2794)
			(stroke
				(width 0.1)
				(type default)
			)
			(layer "B.Fab")
		)
		(fp_line
			(start 0.12065 0.2794)
			(end 0.12065 0.3048)
			(stroke
				(width 0.1)
				(type default)
			)
			(layer "B.Fab")
		)
		(fp_line
			(start -0.12065 -0.2794)
			(end -0.12065 -0.3048)
			(stroke
				(width 0.1)
				(type default)
			)
			(layer "B.Fab")
		)
		(fp_line
			(start 0.12065 -0.2794)
			(end -0.12065 -0.2794)
			(stroke
				(width 0.1)
				(type default)
			)
			(layer "B.Fab")
		)
		(fp_line
			(start -0.67945 -0.3048)
			(end -0.67945 0.3048)
			(stroke
				(width 0.1)
				(type default)
			)
			(layer "B.Fab")
		)
		(fp_line
			(start -0.12065 -0.3048)
			(end -0.67945 -0.3048)
			(stroke
				(width 0.1)
				(type default)
			)
			(layer "B.Fab")
		)
		(fp_line
			(start 0.12065 -0.305054)
			(end 0.12065 -0.2794)
			(stroke
				(width 0.1)
				(type default)
			)
			(layer "B.Fab")
		)
		(fp_line
			(start 0.67945 -0.305054)
			(end 0.12065 -0.305054)
			(stroke
				(width 0.1)
				(type default)
			)
			(layer "B.Fab")
		)
		(pad "1" smd circle
			(at 0.40005 0 90)
			(size 0 0)
			(layers "B.Cu" "B.Mask" "B.Paste")
			(net "P0V9_CPU1_RT_2D")
		)
		(pad "2" smd circle
			(at -0.40005 0 90)
			(size 0 0)
			(layers "B.Cu" "B.Mask" "B.Paste")
			(net "GND")
		)
	)
	(footprint ""
		(layer "B.Cu")
		(at 350.318832 -259.729986 180)
		(property "Reference" "C2611"
			(at 0 0 0)
			(layer "B.SilkS")
			(hide yes)
			(effects
				(font
					(size 1.27 1.27)
				)
				(justify mirror)
			)
		)
		(property "Value" ""
			(at 0 0 0)
			(layer "B.Fab")
			(effects
				(font
					(size 1.27 1.27)
				)
				(justify mirror)
			)
		)
		(duplicate_pad_numbers_are_jumpers no)
		(fp_line
			(start 0.7874 0.4064)
			(end 0.7874 -0.4064)
			(stroke
				(width 0.1524)
				(type default)
			)
			(layer "B.SilkS")
		)
		(fp_line
			(start 0.7874 -0.4064)
			(end -0.7874 -0.4064)
			(stroke
				(width 0.1524)
				(type default)
			)
			(layer "B.SilkS")
		)
		(fp_line
			(start -0.7874 0.4064)
			(end 0.7874 0.4064)
			(stroke
				(width 0.1524)
				(type default)
			)
			(layer "B.SilkS")
		)
		(fp_line
			(start -0.7874 -0.4064)
			(end -0.7874 0.4064)
			(stroke
				(width 0.1524)
				(type default)
			)
			(layer "B.SilkS")
		)
		(fp_line
			(start 0.67945 0.3048)
			(end 0.67945 -0.305054)
			(stroke
				(width 0.1)
				(type default)
			)
			(layer "B.Fab")
		)
		(fp_line
			(start 0.67945 -0.305054)
			(end 0.12065 -0.305054)
			(stroke
				(width 0.1)
				(type default)
			)
			(layer "B.Fab")
		)
		(fp_line
			(start 0.12065 0.3048)
			(end 0.67945 0.3048)
			(stroke
				(width 0.1)
				(type default)
			)
			(layer "B.Fab")
		)
		(fp_line
			(start 0.12065 0.2794)
			(end 0.12065 0.3048)
			(stroke
				(width 0.1)
				(type default)
			)
			(layer "B.Fab")
		)
		(fp_line
			(start 0.12065 -0.2794)
			(end -0.12065 -0.2794)
			(stroke
				(width 0.1)
				(type default)
			)
			(layer "B.Fab")
		)
		(fp_line
			(start 0.12065 -0.305054)
			(end 0.12065 -0.2794)
			(stroke
				(width 0.1)
				(type default)
			)
			(layer "B.Fab")
		)
		(fp_line
			(start -0.120396 0.3048)
			(end -0.120396 0.2794)
			(stroke
				(width 0.1)
				(type default)
			)
			(layer "B.Fab")
		)
		(fp_line
			(start -0.120396 0.2794)
			(end 0.12065 0.2794)
			(stroke
				(width 0.1)
				(type default)
			)
			(layer "B.Fab")
		)
		(fp_line
			(start -0.12065 -0.2794)
			(end -0.12065 -0.3048)
			(stroke
				(width 0.1)
				(type default)
			)
			(layer "B.Fab")
		)
		(fp_line
			(start -0.12065 -0.3048)
			(end -0.67945 -0.3048)
			(stroke
				(width 0.1)
				(type default)
			)
			(layer "B.Fab")
		)
		(fp_line
			(start -0.67945 0.3048)
			(end -0.120396 0.3048)
			(stroke
				(width 0.1)
				(type default)
			)
			(layer "B.Fab")
		)
		(fp_line
			(start -0.67945 -0.3048)
			(end -0.67945 0.3048)
			(stroke
				(width 0.1)
				(type default)
			)
			(layer "B.Fab")
		)
		(pad "1" smd circle
			(at 0.40005 0)
			(size 0 0)
			(layers "B.Cu" "B.Mask" "B.Paste")
			(net "PVDDIO_P0")
		)
		(pad "2" smd circle
			(at -0.40005 0)
			(size 0 0)
			(layers "B.Cu" "B.Mask" "B.Paste")
			(net "GND")
		)
	)
	(footprint ""
		(layer "B.Cu")
		(at 156.746194 -388.011162 -90)
		(property "Reference" "C379"
			(at 0 0 90)
			(layer "B.SilkS")
			(hide yes)
			(effects
				(font
					(size 1.27 1.27)
				)
				(justify mirror)
			)
		)
		(property "Value" ""
			(at 0 0 90)
			(layer "B.Fab")
			(effects
				(font
					(size 1.27 1.27)
				)
				(justify mirror)
			)
		)
		(duplicate_pad_numbers_are_jumpers no)
		(fp_line
			(start -0.299974 0.150114)
			(end 0.299974 0.150114)
			(stroke
				(width 0.1)
				(type default)
			)
			(layer "B.Fab")
		)
		(fp_line
			(start 0.299974 0.150114)
			(end 0.299974 -0.150114)
			(stroke
				(width 0.1)
				(type default)
			)
			(layer "B.Fab")
		)
		(fp_line
			(start -0.299974 -0.150114)
			(end -0.299974 0.150114)
			(stroke
				(width 0.1)
				(type default)
			)
			(layer "B.Fab")
		)
		(fp_line
			(start 0.299974 -0.150114)
			(end -0.299974 -0.150114)
			(stroke
				(width 0.1)
				(type default)
			)
			(layer "B.Fab")
		)
		(pad "1" smd rect
			(at 0.2667 0 90)
			(size 0.3048 0.381)
			(layers "B.Cu" "B.Mask" "B.Paste")
			(net "P1V8_CPU1_RT2_1A")
		)
		(pad "2" smd rect
			(at -0.2667 0 90)
			(size 0.3048 0.381)
			(layers "B.Cu" "B.Mask" "B.Paste")
			(net "GND")
		)
	)
)
